(kicad_pcb
	(version 20260206)
	(generator "pcbnew")
	(generator_version "10.0")
	(general
		(thickness 1.6)
		(legacy_teardrops no)
	)
	(paper "A4")
	(title_block
		(title "Bryce Canyon_IOM_IOC_16318-2_OCP.brd")
		(comment 1 "Bryce Canyon / footprints 75-82 of 1605")
	)
	(layers
		(0 "F.Cu" signal "TOP")
		(4 "In1.Cu" signal "L2GND")
		(6 "In2.Cu" signal "L3")
		(8 "In3.Cu" signal "L4VCC")
		(10 "In4.Cu" signal "L5VCC")
		(12 "In5.Cu" signal "L6")
		(14 "In6.Cu" signal "L7GND")
		(2 "B.Cu" signal "BOTTOM")
		(9 "F.Adhes" user "F.Adhesive")
		(11 "B.Adhes" user "B.Adhesive")
		(13 "F.Paste" user "Package Geometry/Pastemask Top")
		(15 "B.Paste" user "Package Geometry/Pastemask Bottom")
		(5 "F.SilkS" user "Ref Des/Silkscreen Top")
		(7 "B.SilkS" user "Ref Des/Silkscreen Bottom")
		(1 "F.Mask" user "Board Geometry/Soldermask Top")
		(3 "B.Mask" user "Board Geometry/Soldermask Bottom")
		(17 "Dwgs.User" user "User.Drawings")
		(19 "Cmts.User" user "User.Comments")
		(21 "Eco1.User" user "User.Eco1")
		(23 "Eco2.User" user "User.Eco2")
		(25 "Edge.Cuts" user "Board Geometry/Outline")
		(27 "Margin" user)
		(31 "F.CrtYd" user "Package Geometry/Place Bound Top")
		(29 "B.CrtYd" user "Package Geometry/Place Bound Bottom")
		(35 "F.Fab" user "Ref Des/Assembly Top")
		(33 "B.Fab" user "Ref Des/Assembly Bottom")
	)
	(footprint ""
		(layer "F.Cu")
		(at 50.935128 -166.472362 180)
		(property "Reference" "C520"
			(at 0 0 180)
			(layer "F.SilkS")
			(hide yes)
			(effects
				(font
					(size 1.27 1.27)
				)
			)
		)
		(property "Value" "SCD1U25V2KX-2-GP"
			(at 1.1811 -2.7051 180)
			(unlocked yes)
			(layer "F.Fab")
			(hide yes)
			(effects
				(font
					(size 1.016 1.016)
					(thickness 0.1524)
				)
			)
		)
		(property "Device Type" "C402H22"
			(at 1.1811 -4.2291 180)
			(unlocked yes)
			(layer "F.Fab")
			(hide yes)
			(effects
				(font
					(size 1.016 1.016)
					(thickness 0.1524)
				)
			)
		)
		(duplicate_pad_numbers_are_jumpers no)
		(fp_rect
			(start -0.4318 0.9525)
			(end 0.4318 -0.9525)
			(stroke
				(width 0)
				(type default)
			)
			(fill no)
			(layer "F.CrtYd")
		)
		(fp_rect
			(start -0.4318 0.9525)
			(end 0.4318 -0.9525)
			(stroke
				(width 0)
				(type default)
			)
			(fill no)
			(layer "F.Fab")
		)
		(pad "1" smd custom
			(at 0 -0.4445 180)
			(size 0.1524 0.1524)
			(layers "F.Cu" "F.Mask" "F.Paste")
			(net "ADC_P2V5_STBY")
			(options
				(clearance outline)
				(anchor circle)
			)
			(primitives
				(gr_poly
					(pts
						(arc
							(start 0.3048 -0.2032)
							(mid 0.275042 -0.275042)
							(end 0.2032 -0.3048)
						)
						(arc
							(start -0.2032 -0.3048)
							(mid -0.275042 -0.275042)
							(end -0.3048 -0.2032)
						)
						(arc
							(start -0.3048 0.2032)
							(mid -0.275042 0.275042)
							(end -0.2032 0.3048)
						)
						(arc
							(start 0.2032 0.3048)
							(mid 0.275042 0.275042)
							(end 0.3048 0.2032)
						)
					)
					(width 0)
					(fill yes)
				)
			)
		)
		(pad "2" smd custom
			(at 0 0.4445 180)
			(size 0.1524 0.1524)
			(layers "F.Cu" "F.Mask" "F.Paste")
			(net "GND")
			(options
				(clearance outline)
				(anchor circle)
			)
			(primitives
				(gr_poly
					(pts
						(arc
							(start 0.3048 -0.2032)
							(mid 0.275042 -0.275042)
							(end 0.2032 -0.3048)
						)
						(arc
							(start -0.2032 -0.3048)
							(mid -0.275042 -0.275042)
							(end -0.3048 -0.2032)
						)
						(arc
							(start -0.3048 0.2032)
							(mid -0.275042 0.275042)
							(end -0.2032 0.3048)
						)
						(arc
							(start 0.2032 0.3048)
							(mid 0.275042 0.275042)
							(end 0.3048 0.2032)
						)
					)
					(width 0)
					(fill yes)
				)
			)
		)
	)
	(footprint ""
		(layer "F.Cu")
		(at 20.4724 -174.5488)
		(property "Reference" "R532"
			(at 0 0 0)
			(layer "F.SilkS")
			(hide yes)
			(effects
				(font
					(size 1.27 1.27)
				)
			)
		)
		(property "Value" "10KR2F-2-GP"
			(at 0.064008 -3.993896 0)
			(unlocked yes)
			(layer "F.Fab")
			(hide yes)
			(effects
				(font
					(size 1.016 1.016)
					(thickness 0.1524)
				)
			)
		)
		(property "Device Type" "R402H16"
			(at 0.064008 -5.517896 0)
			(unlocked yes)
			(layer "F.Fab")
			(hide yes)
			(effects
				(font
					(size 1.016 1.016)
					(thickness 0.1524)
				)
			)
		)
		(duplicate_pad_numbers_are_jumpers no)
		(fp_line
			(start -0.508 -0.9398)
			(end -0.508 0.9398)
			(stroke
				(width 0.1524)
				(type default)
			)
			(layer "F.SilkS")
		)
		(fp_line
			(start 0.508 -0.9398)
			(end -0.508 -0.9398)
			(stroke
				(width 0.1524)
				(type default)
			)
			(layer "F.SilkS")
		)
		(fp_rect
			(start -0.508 0.9398)
			(end 0.508 -0.9398)
			(stroke
				(width 0)
				(type default)
			)
			(fill no)
			(layer "F.CrtYd")
		)
		(fp_rect
			(start -0.508 0.9398)
			(end 0.508 -0.9398)
			(stroke
				(width 0)
				(type default)
			)
			(fill no)
			(layer "F.Fab")
		)
		(pad "1" smd custom
			(at 0 -0.4445)
			(size 0.1397 0.1397)
			(layers "F.Cu" "F.Mask" "F.Paste")
			(net "P3V3_STBY")
			(options
				(clearance outline)
				(anchor circle)
			)
			(primitives
				(gr_poly
					(pts
						(arc
							(start -0.1778 -0.2794)
							(mid -0.249642 -0.249642)
							(end -0.2794 -0.1778)
						)
						(arc
							(start -0.2794 0.1778)
							(mid -0.249642 0.249642)
							(end -0.1778 0.2794)
						)
						(arc
							(start 0.1778 0.2794)
							(mid 0.249642 0.249642)
							(end 0.2794 0.1778)
						)
						(arc
							(start 0.2794 -0.1778)
							(mid 0.249642 -0.249642)
							(end 0.1778 -0.2794)
						)
					)
					(width 0)
					(fill yes)
				)
			)
		)
		(pad "2" smd custom
			(at 0 0.4445)
			(size 0.1397 0.1397)
			(layers "F.Cu" "F.Mask" "F.Paste")
			(net "PWRGD_P1V2_STBY")
			(options
				(clearance outline)
				(anchor circle)
			)
			(primitives
				(gr_poly
					(pts
						(arc
							(start -0.1778 -0.2794)
							(mid -0.249642 -0.249642)
							(end -0.2794 -0.1778)
						)
						(arc
							(start -0.2794 0.1778)
							(mid -0.249642 0.249642)
							(end -0.1778 0.2794)
						)
						(arc
							(start 0.1778 0.2794)
							(mid 0.249642 0.249642)
							(end 0.2794 0.1778)
						)
						(arc
							(start 0.2794 -0.1778)
							(mid 0.249642 -0.249642)
							(end 0.1778 -0.2794)
						)
					)
					(width 0)
					(fill yes)
				)
			)
		)
	)
	(footprint ""
		(layer "F.Cu")
		(at 185.928 -48.4378 180)
		(property "Reference" "R675"
			(at 0 0 180)
			(layer "F.SilkS")
			(hide yes)
			(effects
				(font
					(size 1.27 1.27)
				)
			)
		)
		(property "Value" "10KR2F-2-GP"
			(at 0.064008 -3.993896 180)
			(unlocked yes)
			(layer "F.Fab")
			(hide yes)
			(effects
				(font
					(size 1.016 1.016)
					(thickness 0.1524)
				)
			)
		)
		(property "Device Type" "R402H16"
			(at 0.064008 -5.517896 180)
			(unlocked yes)
			(layer "F.Fab")
			(hide yes)
			(effects
				(font
					(size 1.016 1.016)
					(thickness 0.1524)
				)
			)
		)
		(duplicate_pad_numbers_are_jumpers no)
		(fp_line
			(start 0.508 -0.9398)
			(end -0.508 -0.9398)
			(stroke
				(width 0.1524)
				(type default)
			)
			(layer "F.SilkS")
		)
		(fp_line
			(start -0.508 -0.9398)
			(end -0.508 0.9398)
			(stroke
				(width 0.1524)
				(type default)
			)
			(layer "F.SilkS")
		)
		(fp_rect
			(start -0.508 0.9398)
			(end 0.508 -0.9398)
			(stroke
				(width 0)
				(type default)
			)
			(fill no)
			(layer "F.CrtYd")
		)
		(fp_rect
			(start -0.508 0.9398)
			(end 0.508 -0.9398)
			(stroke
				(width 0)
				(type default)
			)
			(fill no)
			(layer "F.Fab")
		)
		(pad "1" smd custom
			(at 0 -0.4445 180)
			(size 0.1397 0.1397)
			(layers "F.Cu" "F.Mask" "F.Paste")
			(net "P1V8")
			(options
				(clearance outline)
				(anchor circle)
			)
			(primitives
				(gr_poly
					(pts
						(arc
							(start -0.1778 -0.2794)
							(mid -0.249642 -0.249642)
							(end -0.2794 -0.1778)
						)
						(arc
							(start -0.2794 0.1778)
							(mid -0.249642 0.249642)
							(end -0.1778 0.2794)
						)
						(arc
							(start 0.1778 0.2794)
							(mid 0.249642 0.249642)
							(end 0.2794 0.1778)
						)
						(arc
							(start 0.2794 -0.1778)
							(mid 0.249642 -0.249642)
							(end 0.1778 -0.2794)
						)
					)
					(width 0)
					(fill yes)
				)
			)
		)
		(pad "2" smd custom
			(at 0 0.4445 180)
			(size 0.1397 0.1397)
			(layers "F.Cu" "F.Mask" "F.Paste")
			(net "XM_RB")
			(options
				(clearance outline)
				(anchor circle)
			)
			(primitives
				(gr_poly
					(pts
						(arc
							(start -0.1778 -0.2794)
							(mid -0.249642 -0.249642)
							(end -0.2794 -0.1778)
						)
						(arc
							(start -0.2794 0.1778)
							(mid -0.249642 0.249642)
							(end -0.1778 0.2794)
						)
						(arc
							(start 0.1778 0.2794)
							(mid 0.249642 0.249642)
							(end 0.2794 0.1778)
						)
						(arc
							(start 0.2794 -0.1778)
							(mid 0.249642 -0.249642)
							(end 0.1778 -0.2794)
						)
					)
					(width 0)
					(fill yes)
				)
			)
		)
	)
	(footprint ""
		(layer "F.Cu")
		(at 207.946752 -102.85857)
		(property "Reference" "R608"
			(at 0 0 0)
			(layer "F.SilkS")
			(hide yes)
			(effects
				(font
					(size 1.27 1.27)
				)
			)
		)
		(property "Value" "0R2J-2-GP"
			(at 0.064008 -3.993896 0)
			(unlocked yes)
			(layer "F.Fab")
			(hide yes)
			(effects
				(font
					(size 1.016 1.016)
					(thickness 0.1524)
				)
			)
		)
		(property "Device Type" "R402H16"
			(at 0.064008 -5.517896 0)
			(unlocked yes)
			(layer "F.Fab")
			(hide yes)
			(effects
				(font
					(size 1.016 1.016)
					(thickness 0.1524)
				)
			)
		)
		(duplicate_pad_numbers_are_jumpers no)
		(fp_line
			(start -0.508 -0.9398)
			(end -0.508 0.9398)
			(stroke
				(width 0.1524)
				(type default)
			)
			(layer "F.SilkS")
		)
		(fp_line
			(start 0.508 -0.9398)
			(end -0.508 -0.9398)
			(stroke
				(width 0.1524)
				(type default)
			)
			(layer "F.SilkS")
		)
		(fp_rect
			(start -0.508 0.9398)
			(end 0.508 -0.9398)
			(stroke
				(width 0)
				(type default)
			)
			(fill no)
			(layer "F.CrtYd")
		)
		(fp_rect
			(start -0.508 0.9398)
			(end 0.508 -0.9398)
			(stroke
				(width 0)
				(type default)
			)
			(fill no)
			(layer "F.Fab")
		)
		(pad "1" smd custom
			(at 0 -0.4445)
			(size 0.1397 0.1397)
			(layers "F.Cu" "F.Mask" "F.Paste")
			(net "IOC_EEPROM_SDA")
			(options
				(clearance outline)
				(anchor circle)
			)
			(primitives
				(gr_poly
					(pts
						(arc
							(start -0.1778 -0.2794)
							(mid -0.249642 -0.249642)
							(end -0.2794 -0.1778)
						)
						(arc
							(start -0.2794 0.1778)
							(mid -0.249642 0.249642)
							(end -0.1778 0.2794)
						)
						(arc
							(start 0.1778 0.2794)
							(mid 0.249642 0.249642)
							(end 0.2794 0.1778)
						)
						(arc
							(start 0.2794 -0.1778)
							(mid 0.249642 -0.249642)
							(end 0.1778 -0.2794)
						)
					)
					(width 0)
					(fill yes)
				)
			)
		)
		(pad "2" smd custom
			(at 0 0.4445)
			(size 0.1397 0.1397)
			(layers "F.Cu" "F.Mask" "F.Paste")
			(net "SBL_SDA")
			(options
				(clearance outline)
				(anchor circle)
			)
			(primitives
				(gr_poly
					(pts
						(arc
							(start -0.1778 -0.2794)
							(mid -0.249642 -0.249642)
							(end -0.2794 -0.1778)
						)
						(arc
							(start -0.2794 0.1778)
							(mid -0.249642 0.249642)
							(end -0.1778 0.2794)
						)
						(arc
							(start 0.1778 0.2794)
							(mid 0.249642 0.249642)
							(end 0.2794 0.1778)
						)
						(arc
							(start 0.2794 -0.1778)
							(mid 0.249642 -0.249642)
							(end 0.1778 -0.2794)
						)
					)
					(width 0)
					(fill yes)
				)
			)
		)
	)
	(footprint ""
		(layer "F.Cu")
		(at 212.3567 -125.134116 180)
		(property "Reference" "C249"
			(at 0 0 180)
			(layer "F.SilkS")
			(hide yes)
			(effects
				(font
					(size 1.27 1.27)
				)
			)
		)
		(property "Value" "SC10U6D3V5KX-4GP"
			(at -0.0762 -6.1214 180)
			(unlocked yes)
			(layer "F.Fab")
			(hide yes)
			(effects
				(font
					(size 1.016 1.016)
					(thickness 0.1524)
				)
			)
		)
		(property "Device Type" "C805H58"
			(at -0.0762 -8.1534 180)
			(unlocked yes)
			(layer "F.Fab")
			(hide yes)
			(effects
				(font
					(size 1.016 1.016)
					(thickness 0.1524)
				)
			)
		)
		(duplicate_pad_numbers_are_jumpers no)
		(fp_line
			(start 0.635 0)
			(end -0.635 0)
			(stroke
				(width 0.508)
				(type default)
			)
			(layer "F.SilkS")
		)
		(fp_rect
			(start -0.9652 1.778)
			(end 0.9652 -1.778)
			(stroke
				(width 0)
				(type default)
			)
			(fill no)
			(layer "F.CrtYd")
		)
		(fp_poly
			(pts
				(xy -0.9652 -1.778) (xy 0.9652 -1.778) (xy 0.9652 1.778) (xy -0.9652 1.778)
			)
			(stroke
				(width 0)
				(type default)
			)
			(fill no)
			(layer "F.Fab")
		)
		(pad "1" smd rect
			(at 0 -0.9652 180)
			(size 1.397 1.143)
			(layers "F.Cu" "F.Mask" "F.Paste")
			(net "P1V5_OUT")
		)
		(pad "2" smd rect
			(at 0 0.9652 180)
			(size 1.397 1.143)
			(layers "F.Cu" "F.Mask" "F.Paste")
			(net "GND")
		)
	)
	(footprint ""
		(layer "F.Cu")
		(at 92.71 -179.3748 90)
		(property "Reference" "U106"
			(at 0 0 90)
			(layer "F.SilkS")
			(hide yes)
			(effects
				(font
					(size 1.27 1.27)
				)
			)
		)
		(property "Value" "SNLVC1G14DBVR-GP"
			(at 0 -5.1308 90)
			(unlocked yes)
			(layer "F.Fab")
			(hide yes)
			(effects
				(font
					(size 1.016 1.016)
					(thickness 0.1524)
				)
			)
		)
		(property "Device Type" "SOT-23-5H58"
			(at 0 -6.7564 90)
			(unlocked yes)
			(layer "F.Fab")
			(hide yes)
			(effects
				(font
					(size 1.016 1.016)
					(thickness 0.1524)
				)
			)
		)
		(duplicate_pad_numbers_are_jumpers no)
		(fp_line
			(start 1.778 -2.286)
			(end -1.778 -2.286)
			(stroke
				(width 0.1524)
				(type default)
			)
			(layer "F.SilkS")
		)
		(fp_line
			(start -1.778 -2.286)
			(end -1.778 2.286)
			(stroke
				(width 0.1524)
				(type default)
			)
			(layer "F.SilkS")
		)
		(fp_line
			(start -0.7112 2.2352)
			(end -1.7272 2.2352)
			(stroke
				(width 0.3302)
				(type default)
			)
			(layer "F.SilkS")
		)
		(fp_line
			(start -1.7272 2.2352)
			(end -1.7272 0.762)
			(stroke
				(width 0.3302)
				(type default)
			)
			(layer "F.SilkS")
		)
		(fp_line
			(start 1.778 2.286)
			(end 1.778 -2.286)
			(stroke
				(width 0.1524)
				(type default)
			)
			(layer "F.SilkS")
		)
		(fp_line
			(start -0.254 2.286)
			(end 1.778 2.286)
			(stroke
				(width 0.1524)
				(type default)
			)
			(layer "F.SilkS")
		)
		(fp_line
			(start -1.778 2.286)
			(end 1.778 2.286)
			(stroke
				(width 0.1524)
				(type default)
			)
			(layer "F.SilkS")
		)
		(fp_line
			(start -1.778 2.286)
			(end -0.254 2.286)
			(stroke
				(width 0.1524)
				(type default)
			)
			(layer "F.SilkS")
		)
		(fp_poly
			(pts
				(xy -0.9652 2.4384) (xy -1.3208 2.794) (xy -0.6096 2.794)
			)
			(stroke
				(width 0)
				(type default)
			)
			(fill yes)
			(layer "F.SilkS")
		)
		(fp_rect
			(start -1.778 2.286)
			(end 1.778 -2.286)
			(stroke
				(width 0)
				(type default)
			)
			(fill no)
			(layer "F.CrtYd")
		)
		(fp_rect
			(start -1.778 2.286)
			(end 1.778 -2.286)
			(stroke
				(width 0)
				(type default)
			)
			(fill no)
			(layer "F.Fab")
		)
		(pad "1" smd rect
			(at -0.94996 1.143 90)
			(size 0.508 1.524)
			(layers "F.Cu" "F.Mask" "F.Paste")
			(net "Net_132")
		)
		(pad "2" smd rect
			(at 0 1.143 90)
			(size 0.508 1.524)
			(layers "F.Cu" "F.Mask" "F.Paste")
			(net "PWRGD_P3V3_STBY")
		)
		(pad "3" smd rect
			(at 0.94996 1.143 90)
			(size 0.508 1.524)
			(layers "F.Cu" "F.Mask" "F.Paste")
			(net "GND")
		)
		(pad "4" smd rect
			(at 0.94996 -1.143 90)
			(size 0.508 1.524)
			(layers "F.Cu" "F.Mask" "F.Paste")
			(net "PWRGD_P3V3_STBY_N")
		)
		(pad "5" smd rect
			(at -0.94996 -1.143 90)
			(size 0.508 1.524)
			(layers "F.Cu" "F.Mask" "F.Paste")
			(net "P3V3_STBY")
		)
	)
	(footprint ""
		(layer "F.Cu")
		(at 156.464 -141.0716 -90)
		(property "Reference" "G5"
			(at 0 0 270)
			(layer "F.SilkS")
			(hide yes)
			(effects
				(font
					(size 1.27 1.27)
				)
			)
		)
		(property "Value" "COPPER-CLOSE-GP-U"
			(at 0.0762 -2.8702 270)
			(unlocked yes)
			(layer "F.Fab")
			(hide yes)
			(effects
				(font
					(size 1.016 1.016)
					(thickness 0.1524)
				)
			)
		)
		(property "Device Type" "CON2C-U"
			(at 0.0762 -4.3942 270)
			(unlocked yes)
			(layer "F.Fab")
			(hide yes)
			(effects
				(font
					(size 1.016 1.016)
					(thickness 0.1524)
				)
			)
		)
		(duplicate_pad_numbers_are_jumpers no)
		(fp_rect
			(start -0.9398 0.9652)
			(end 0.9398 -0.9652)
			(stroke
				(width 0)
				(type default)
			)
			(fill no)
			(layer "F.CrtYd")
		)
		(fp_rect
			(start -0.9398 0.9652)
			(end 0.9398 -0.9652)
			(stroke
				(width 0)
				(type default)
			)
			(fill no)
			(layer "F.Fab")
		)
		(pad "1" smd custom
			(at 0 -0.5334 270)
			(size 0.17145 0.17145)
			(layers "F.Cu" "F.Mask" "F.Paste")
			(net "AGND_P1V8_STBY")
			(options
				(clearance outline)
				(anchor circle)
			)
			(primitives
				(gr_poly
					(pts
						(xy -0.127 0.3429) (xy -0.127 0.1651) (xy -0.635 -0.3429) (xy 0.635 -0.3429) (xy 0.127 0.1651)
						(xy 0.127 0.3429)
					)
					(width 0)
					(fill yes)
				)
			)
		)
		(pad "2" smd custom
			(at 0 0.5334 270)
			(size 0.17145 0.17145)
			(layers "F.Cu" "F.Mask" "F.Paste")
			(net "GND")
			(options
				(clearance outline)
				(anchor circle)
			)
			(primitives
				(gr_poly
					(pts
						(xy -0.635 0.3429) (xy -0.127 -0.1651) (xy -0.127 -0.3429) (xy 0.127 -0.3429) (xy 0.127 -0.1651)
						(xy 0.635 0.3429)
					)
					(width 0)
					(fill yes)
				)
			)
		)
	)
	(footprint ""
		(layer "F.Cu")
		(at 200.7616 -106.1974)
		(property "Reference" "R553"
			(at 0 0 0)
			(layer "F.SilkS")
			(hide yes)
			(effects
				(font
					(size 1.27 1.27)
				)
			)
		)
		(property "Value" "10KR2F-2-GP"
			(at 0.064008 -3.993896 0)
			(unlocked yes)
			(layer "F.Fab")
			(hide yes)
			(effects
				(font
					(size 1.016 1.016)
					(thickness 0.1524)
				)
			)
		)
		(property "Device Type" "R402H16"
			(at 0.064008 -5.517896 0)
			(unlocked yes)
			(layer "F.Fab")
			(hide yes)
			(effects
				(font
					(size 1.016 1.016)
					(thickness 0.1524)
				)
			)
		)
		(duplicate_pad_numbers_are_jumpers no)
		(fp_line
			(start -0.508 -0.9398)
			(end -0.508 0.9398)
			(stroke
				(width 0.1524)
				(type default)
			)
			(layer "F.SilkS")
		)
		(fp_line
			(start 0.508 -0.9398)
			(end -0.508 -0.9398)
			(stroke
				(width 0.1524)
				(type default)
			)
			(layer "F.SilkS")
		)
		(fp_rect
			(start -0.508 0.9398)
			(end 0.508 -0.9398)
			(stroke
				(width 0)
				(type default)
			)
			(fill no)
			(layer "F.CrtYd")
		)
		(fp_rect
			(start -0.508 0.9398)
			(end 0.508 -0.9398)
			(stroke
				(width 0)
				(type default)
			)
			(fill no)
			(layer "F.Fab")
		)
		(pad "1" smd custom
			(at 0 -0.4445)
			(size 0.1397 0.1397)
			(layers "F.Cu" "F.Mask" "F.Paste")
			(net "P0V975")
			(options
				(clearance outline)
				(anchor circle)
			)
			(primitives
				(gr_poly
					(pts
						(arc
							(start -0.1778 -0.2794)
							(mid -0.249642 -0.249642)
							(end -0.2794 -0.1778)
						)
						(arc
							(start -0.2794 0.1778)
							(mid -0.249642 0.249642)
							(end -0.1778 0.2794)
						)
						(arc
							(start 0.1778 0.2794)
							(mid 0.249642 0.249642)
							(end 0.2794 0.1778)
						)
						(arc
							(start 0.2794 -0.1778)
							(mid 0.249642 -0.249642)
							(end 0.1778 -0.2794)
						)
					)
					(width 0)
					(fill yes)
				)
			)
		)
		(pad "2" smd custom
			(at 0 0.4445)
			(size 0.1397 0.1397)
			(layers "F.Cu" "F.Mask" "F.Paste")
			(net "GND")
			(options
				(clearance outline)
				(anchor circle)
			)
			(primitives
				(gr_poly
					(pts
						(arc
							(start -0.1778 -0.2794)
							(mid -0.249642 -0.249642)
							(end -0.2794 -0.1778)
						)
						(arc
							(start -0.2794 0.1778)
							(mid -0.249642 0.249642)
							(end -0.1778 0.2794)
						)
						(arc
							(start 0.1778 0.2794)
							(mid 0.249642 0.249642)
							(end 0.2794 0.1778)
						)
						(arc
							(start 0.2794 -0.1778)
							(mid 0.249642 -0.249642)
							(end 0.1778 -0.2794)
						)
					)
					(width 0)
					(fill yes)
				)
			)
		)
	)
)
